# T6G (Grand Teton) — schematic netlist excerpt (pin names and nets, part order shuffled) for the footprints in the layout excerpt that follows; sources: Cadence DE-HDL packaged netlist, KiCad conversion of 04192023_DAF0TMB3IC0_F0TG_MB_C_brd_V02_OCP.brd

J19  SCONN288_DDR506112002KQ  IO  pkg DDR288S_1-1VXC  page 89
  VIN_BULK0  = P12V_MEM_CPU0
  RFU0  = NC
  VIN_MGMT  = P3V3_AUX
  HSCL  = I3C_SPD_DDRD_CPU0_SCL
  HSDA  = I3C_SPD_DDRD_CPU0_SDA
  VSS0  = GND
  DQ0_A  = M_D_CPU0_SA_DQ<0>
  VSS1  = GND
  DQ1_A  = M_D_CPU0_SA_DQ<1>
  VSS2  = GND
  DQS0_A_T  = M_D_CPU0_SA_DQS_DP<0>
  DQS0_A_C  = M_D_CPU0_SA_DQS_DN<0>
  VSS3  = GND
  DQ4_A  = M_D_CPU0_SA_DQ<4>
  VSS4  = GND
  DQ5_A  = M_D_CPU0_SA_DQ<5>
  VSS5  = GND
  DQ8_A  = M_D_CPU0_SA_DQ<8>
  VSS6  = GND
  DQ9_A  = M_D_CPU0_SA_DQ<9>
  VSS7  = GND
  DQS1_A_T  = M_D_CPU0_SA_DQS_DP<1>
  DQS1_A_C  = M_D_CPU0_SA_DQS_DN<1>
  VSS8  = GND
  DQ12_A  = M_D_CPU0_SA_DQ<12>
  VSS9  = GND
  DQ13_A  = M_D_CPU0_SA_DQ<13>
  VSS10  = GND
  DQ16_A  = M_D_CPU0_SA_DQ<16>
  VSS11  = GND
  DQ17_A  = M_D_CPU0_SA_DQ<17>
  VSS12  = GND
  DQS2_A_T  = M_D_CPU0_SA_DQS_DP<2>
  DQS2_A_C  = M_D_CPU0_SA_DQS_DN<2>
  VSS13  = GND
  DQ20_A  = M_D_CPU0_SA_DQ<20>
  VSS14  = GND
  DQ21_A  = M_D_CPU0_SA_DQ<21>
  VSS15  = GND
  DQ24_A  = M_D_CPU0_SA_DQ<24>
  VSS16  = GND
  DQ25_A  = M_D_CPU0_SA_DQ<25>
  VSS17  = GND
  DQS3_A_T  = M_D_CPU0_SA_DQS_DP<3>
  DQS3_A_C  = M_D_CPU0_SA_DQS_DN<3>
  VSS18  = GND
  DQ28_A  = M_D_CPU0_SA_DQ<28>
  VSS19  = GND
  DQ29_A  = M_D_CPU0_SA_DQ<29>
  VSS20  = GND
  CB0_A  = M_D_CPU0_SA_CB<0>
  VSS21  = GND
  CB1_A  = M_D_CPU0_SA_CB<1>
  VSS22  = GND
  DQS4_A_T  = M_D_CPU0_SA_DQS_DP<4>
  DQS4_A_C  = M_D_CPU0_SA_DQS_DN<4>
  VSS23  = GND
  CB4_A  = M_D_CPU0_SA_CB<4>
  VSS24  = GND
  CB5_A  = M_D_CPU0_SA_CB<5>
  VSS25  = GND
  ALERT_N  = M_D_CPU0_ALERT_N
  VSS26  = GND
  CS0_A_N  = M_D_CPU0_SA_CS_N<0>
  VSS27  = GND
  CA0_A  = M_D_CPU0_SA_CA<0>
  VSS28  = GND
  CA2_A  = M_D_CPU0_SA_CA<2>
  VSS29  = GND
  CA4_A  = M_D_CPU0_SA_CA<4>
  VSS30  = GND
  CA6_A  = M_D_CPU0_SA_CA<6>
  VSS31  = GND
  PAR_A  = M_D_CPU0_SA_PAR
  VSS32  = GND
  CA0_B  = M_D_CPU0_SB_CA<0>
  VSS33  = GND
  CA2_B  = M_D_CPU0_SB_CA<2>
  VSS34  = GND
  CA4_B  = M_D_CPU0_SB_CA<4>
  VSS35  = GND
  CA6_B  = M_D_CPU0_SB_CA<6>
  VSS36  = GND
  CS0_B_N  = M_D_CPU0_SB_CS_N<0>
  VSS37  = GND
  \lbd||rsp_a_n\  = M_D_CPU0_SA_RSP<0>
  \lbs||rsp_b_n\  = M_D_CPU0_SB_RSP<0>
  VSS38  = GND
  CB4_B  = M_D_CPU0_SB_CB<4>
  VSS39  = GND
  CB5_B  = M_D_CPU0_SB_CB<5>
  VSS40  = GND
  \dqs9_b_t||tdqs9_b_t||dbi4_b_n\  = M_D_CPU0_SB_DQS_DP<9>
  \dqs9_b_c||tdqs9_b_c\  = M_D_CPU0_SB_DQS_DN<9>
  VSS41  = GND
  CB0_B  = M_D_CPU0_SB_CB<0>
  VSS42  = GND
  CB1_B  = M_D_CPU0_SB_CB<1>
  VSS43  = GND
  DQ0_B  = M_D_CPU0_SB_DQ<0>
  VSS44  = GND
  DQ1_B  = M_D_CPU0_SB_DQ<1>
  VSS45  = GND
  DQS0_B_T  = M_D_CPU0_SB_DQS_DP<0>
  DQS0_B_C  = M_D_CPU0_SB_DQS_DN<0>
  VSS46  = GND
  DQ4_B  = M_D_CPU0_SB_DQ<4>
  VSS47  = GND
  DQ5_B  = M_D_CPU0_SB_DQ<5>
  VSS48  = GND
  DQ8_B  = M_D_CPU0_SB_DQ<8>
  VSS49  = GND
  DQ9_B  = M_D_CPU0_SB_DQ<9>
  VSS50  = GND
  DQS1_B_T  = M_D_CPU0_SB_DQS_DP<1>
  DQS1_B_C  = M_D_CPU0_SB_DQS_DN<1>
  VSS51  = GND
  DQ12_B  = M_D_CPU0_SB_DQ<12>
  VSS52  = GND
  DQ13_B  = M_D_CPU0_SB_DQ<13>
  VSS53  = GND
  DQ16_B  = M_D_CPU0_SB_DQ<16>
  VSS54  = GND
  DQ17_B  = M_D_CPU0_SB_DQ<17>
  VSS55  = GND
  DQS2_B_T  = M_D_CPU0_SB_DQS_DP<2>
  DQS2_B_C  = M_D_CPU0_SB_DQS_DN<2>
  VSS56  = GND
  DQ20_B  = M_D_CPU0_SB_DQ<20>
  VSS57  = GND
  DQ21_B  = M_D_CPU0_SB_DQ<21>
  VSS58  = GND
  DQ24_B  = M_D_CPU0_SB_DQ<24>
  VSS59  = GND
  DQ25_B  = M_D_CPU0_SB_DQ<25>
  VSS60  = GND
  DQS3_B_T  = M_D_CPU0_SB_DQS_DP<3>
  DQS3_B_C  = M_D_CPU0_SB_DQS_DN<3>
  VSS61  = GND
  DQ28_B  = M_D_CPU0_SB_DQ<28>
  VSS62  = GND
  DQ29_B  = M_D_CPU0_SB_DQ<29>
  VSS63  = GND
  RFU1  = NC
  VIN_BULK1  = P12V_MEM_CPU0
  VIN_BULK2  = P12V_MEM_CPU0
  \pwr_good||fail_n\  = PWRGD_CHD_CPU0_DIMM
  HAS  = PD_CHD_CPU0_DIMM_SAA
  RFU2  = NC
  RFU3  = NC
  VSS64  = GND
  DQ2_A  = M_D_CPU0_SA_DQ<2>
  VSS65  = GND
  DQ3_A  = M_D_CPU0_SA_DQ<3>
  VSS66  = GND
  \dqs5_a_c||tdqs5_a_c||dqs5_a_t||tdqs5_a_t\  = M_D_CPU0_SA_DQS_DN<5>
  \dqs5_a_t||tdqs5_a_t\  = M_D_CPU0_SA_DQS_DP<5>
  VSS67  = GND
  DQ6_A  = M_D_CPU0_SA_DQ<6>
  VSS68  = GND
  DQ7_A  = M_D_CPU0_SA_DQ<7>
  VSS69  = GND
  DQ10_A  = M_D_CPU0_SA_DQ<10>
  VSS70  = GND
  DQ11_A  = M_D_CPU0_SA_DQ<11>
  VSS71  = GND
  \dqs6_a_c||tdqs6_a_c||dqs6_a_t||tdqs6_a_t\  = M_D_CPU0_SA_DQS_DN<6>
  \dqs6_a_t||tdqs6_a_t\  = M_D_CPU0_SA_DQS_DP<6>
  VSS72  = GND
  DQ14_A  = M_D_CPU0_SA_DQ<14>
  VSS73  = GND
  DQ15_A  = M_D_CPU0_SA_DQ<15>
  VSS74  = GND
  DQ18_A  = M_D_CPU0_SA_DQ<18>
  VSS75  = GND
  DQ19_A  = M_D_CPU0_SA_DQ<19>
  VSS76  = GND
  \dqs7_a_c||tdqs7_a_c\  = M_D_CPU0_SA_DQS_DN<7>
  \dqs7_a_t||tdqs7_a_t\  = M_D_CPU0_SA_DQS_DP<7>
  VSS77  = GND
  DQ22_A  = M_D_CPU0_SA_DQ<22>
  VSS78  = GND
  DQ23_A  = M_D_CPU0_SA_DQ<23>
  VSS79  = GND
  DQ26_A  = M_D_CPU0_SA_DQ<26>
  VSS80  = GND
  DQ27_A  = M_D_CPU0_SA_DQ<27>
  VSS81  = GND
  \dqs8_a_c||tdqs8_a_c\  = M_D_CPU0_SA_DQS_DN<8>
  \dqs8_a_t||tdqs8_a_t\  = M_D_CPU0_SA_DQS_DP<8>
  VSS82  = GND
  DQ30_A  = M_D_CPU0_SA_DQ<30>
  VSS83  = GND
  DQ31_A  = M_D_CPU0_SA_DQ<31>
  VSS84  = GND
  CB2_A  = M_D_CPU0_SA_CB<2>
  VSS85  = GND
  CB3_A  = M_D_CPU0_SA_CB<3>
  VSS86  = GND
  \dqs9_a_c||tdqs9_a_c\  = M_D_CPU0_SA_DQS_DN<9>
  \dqs9_a_t||tdqs9_a_t\  = M_D_CPU0_SA_DQS_DP<9>
  VSS87  = GND
  CB6_A  = M_D_CPU0_SA_CB<6>
  VSS88  = GND
  CB7_A  = M_D_CPU0_SA_CB<7>
  VSS89  = GND
  RESET_N  = M_D_CPU0_RESET_N
  VSS90  = GND
  CS1_A_N  = M_D_CPU0_SA_CS_N<1>
  VSS91  = GND
  CA1_A  = M_D_CPU0_SA_CA<1>
  VSS92  = GND
  CA3_A  = M_D_CPU0_SA_CA<3>
  VSS93  = GND
  CA5_A  = M_D_CPU0_SA_CA<5>
  VSS94  = GND
  CK_T  = M_D_CPU0_CLK_DP<0>
  CK_C  = M_D_CPU0_CLK_DN<0>
  VSS95  = GND
  RFU4  = NC
  CA1_B  = M_D_CPU0_SB_CA<1>
  VSS96  = GND
  CA3_B  = M_D_CPU0_SB_CA<3>
  VSS97  = GND
  CA5_B  = M_D_CPU0_SB_CA<5>
  VSS98  = GND
  PAR_B  = M_D_CPU0_SB_PAR
  VSS99  = GND
  CS1_B_N  = M_D_CPU0_SB_CS_N<1>
  VSS100  = GND
  RFU5  = NC
  RFU6  = NC
  VSS101  = GND
  CB6_B  = M_D_CPU0_SB_CB<6>
  VSS102  = GND
  CB7_B  = M_D_CPU0_SB_CB<7>
  VSS103  = GND
  DQS4_B_C  = M_D_CPU0_SB_DQS_DN<4>
  DQS4_B_T  = M_D_CPU0_SB_DQS_DP<4>
  VSS104  = GND
  CB2_B  = M_D_CPU0_SB_CB<2>
  VSS105  = GND
  CB3_B  = M_D_CPU0_SB_CB<3>
  VSS106  = GND
  DQ2_B  = M_D_CPU0_SB_DQ<2>
  VSS107  = GND
  DQ3_B  = M_D_CPU0_SB_DQ<3>
  VSS108  = GND
  \dqs5_b_c||tdqs5_b_c\  = M_D_CPU0_SB_DQS_DN<5>
  \dqs5_b_t||tdqs5_b_t\  = M_D_CPU0_SB_DQS_DP<5>
  VSS109  = GND
  DQ6_B  = M_D_CPU0_SB_DQ<6>
  VSS110  = GND
  DQ7_B  = M_D_CPU0_SB_DQ<7>
  VSS111  = GND
  DQ10_B  = M_D_CPU0_SB_DQ<10>
  VSS112  = GND
  DQ11_B  = M_D_CPU0_SB_DQ<11>
  VSS113  = GND
  \dqs6_b_c||tdqs6_b_c\  = M_D_CPU0_SB_DQS_DN<6>
  \dqs6_b_t||tdqs6_b_t\  = M_D_CPU0_SB_DQS_DP<6>
  VSS114  = GND
  DQ14_B  = M_D_CPU0_SB_DQ<14>
  VSS115  = GND
  DQ15_B  = M_D_CPU0_SB_DQ<15>
  VSS116  = GND
  DQ18_B  = M_D_CPU0_SB_DQ<18>
  VSS117  = GND
  DQ19_B  = M_D_CPU0_SB_DQ<19>
  VSS118  = GND
  \dqs7_b_c||tdqs7_b_c\  = M_D_CPU0_SB_DQS_DN<7>
  \dqs7_b_t||tdqs7_b_t\  = M_D_CPU0_SB_DQS_DP<7>
  VSS119  = GND
  DQ22_B  = M_D_CPU0_SB_DQ<22>
  VSS120  = GND
  DQ23_B  = M_D_CPU0_SB_DQ<23>
  VSS121  = GND
  DQ26_B  = M_D_CPU0_SB_DQ<26>
  VSS122  = GND
  DQ27_B  = M_D_CPU0_SB_DQ<27>
  VSS123  = GND
  \dqs8_b_c||tdqs8_b_c\  = M_D_CPU0_SB_DQS_DN<8>
  \dqs8_b_t||tdqs8_b_t\  = M_D_CPU0_SB_DQS_DP<8>
  VSS124  = GND
  DQ30_B  = M_D_CPU0_SB_DQ<30>
  VSS125  = GND
  DQ31_B  = M_D_CPU0_SB_DQ<31>
  VSS126  = GND
  G1  = GND
  G2  = GND
  G3  = GND

(kicad_pcb
	(version 20260206)
	(generator "pcbnew")
	(generator_version "10.0")
	(general
		(thickness 1.6)
		(legacy_teardrops no)
	)
	(paper "A4")
	(title_block
		(title "04192023_DAF0TMB3IC0_F0TG_MB_C_brd_V02_OCP.brd")
		(comment 1 "Grand Teton / footprint 2350 of 8354 (J19), pads 185-230 of 291")
	)
	(layers
		(0 "F.Cu" signal "TOP")
		(4 "In1.Cu" signal "GND")
		(6 "In2.Cu" signal "IN1")
		(8 "In3.Cu" signal "GND1")
		(10 "In4.Cu" signal "IN2")
		(12 "In5.Cu" signal "GND2")
		(14 "In6.Cu" signal "IN3")
		(16 "In7.Cu" signal "GND3")
		(18 "In8.Cu" signal "VCC")
		(20 "In9.Cu" signal "VCC1")
		(22 "In10.Cu" signal "GND4")
		(24 "In11.Cu" signal "IN4")
		(26 "In12.Cu" signal "GND5")
		(28 "In13.Cu" signal "IN5")
		(30 "In14.Cu" signal "GND6")
		(32 "In15.Cu" signal "IN6")
		(34 "In16.Cu" signal "GND7")
		(2 "B.Cu" signal "BOTTOM")
		(9 "F.Adhes" user "F.Adhesive")
		(11 "B.Adhes" user "B.Adhesive")
		(13 "F.Paste" user "Package Geometry/Pastemask Top")
		(15 "B.Paste" user "Package Geometry/Pastemask Bottom")
		(5 "F.SilkS" user "Ref Des/Silkscreen Top")
		(7 "B.SilkS" user "Ref Des/Silkscreen Bottom")
		(1 "F.Mask" user "Board Geometry/Soldermask Top")
		(3 "B.Mask" user "Board Geometry/Soldermask Bottom")
		(17 "Dwgs.User" user "User.Drawings")
		(19 "Cmts.User" user "User.Comments")
		(21 "Eco1.User" user "User.Eco1")
		(23 "Eco2.User" user "User.Eco2")
		(25 "Edge.Cuts" user "Board Geometry/Outline")
		(27 "Margin" user)
		(31 "F.CrtYd" user "Package Geometry/Place Bound Top")
		(29 "B.CrtYd" user "Package Geometry/Place Bound Bottom")
		(35 "F.Fab" user "Ref Des/Assembly Top")
		(33 "B.Fab" user "Ref Des/Assembly Bottom")
	)
	(footprint ""
		(layer "F.Cu")
		(at 282.685998 -255.560068 180)
		(property "Reference" "J19"
			(at -2.2098 -81.984088 0)
			(unlocked yes)
			(layer "F.SilkS")
			(effects
				(font
					(size 0.7874 0.5842)
					(thickness 0.1524)
				)
			)
		)
		(property "Value" ""
			(at 0 0 180)
			(layer "F.Fab")
			(effects
				(font
					(size 1.27 1.27)
				)
			)
		)
		(duplicate_pad_numbers_are_jumpers no)
		(pad "185" smd rect
			(at 2.050034 -29.325062 90)
			(size 0.519938 1.4986)
			(layers "F.Cu" "F.Mask" "F.Paste")
			(net "M_D_CPU0_SA_DQ<26>")
		)
		(pad "186" smd rect
			(at 2.050034 -28.474924 90)
			(size 0.519938 1.4986)
			(layers "F.Cu" "F.Mask" "F.Paste")
			(net "GND")
		)
		(pad "187" smd rect
			(at 2.050034 -27.62504 90)
			(size 0.519938 1.4986)
			(layers "F.Cu" "F.Mask" "F.Paste")
			(net "M_D_CPU0_SA_DQ<27>")
		)
		(pad "188" smd rect
			(at 2.050034 -26.774902 90)
			(size 0.519938 1.4986)
			(layers "F.Cu" "F.Mask" "F.Paste")
			(net "GND")
		)
		(pad "189" smd rect
			(at 2.050034 -25.925018 90)
			(size 0.519938 1.4986)
			(layers "F.Cu" "F.Mask" "F.Paste")
			(net "M_D_CPU0_SA_DQS_DN<8>")
		)
		(pad "190" smd rect
			(at 2.050034 -25.07488 90)
			(size 0.519938 1.4986)
			(layers "F.Cu" "F.Mask" "F.Paste")
			(net "M_D_CPU0_SA_DQS_DP<8>")
		)
		(pad "191" smd rect
			(at 2.050034 -24.224996 90)
			(size 0.519938 1.4986)
			(layers "F.Cu" "F.Mask" "F.Paste")
			(net "GND")
		)
		(pad "192" smd rect
			(at 2.050034 -23.375112 90)
			(size 0.519938 1.4986)
			(layers "F.Cu" "F.Mask" "F.Paste")
			(net "M_D_CPU0_SA_DQ<30>")
		)
		(pad "193" smd rect
			(at 2.050034 -22.524974 90)
			(size 0.519938 1.4986)
			(layers "F.Cu" "F.Mask" "F.Paste")
			(net "GND")
		)
		(pad "194" smd rect
			(at 2.050034 -21.67509 90)
			(size 0.519938 1.4986)
			(layers "F.Cu" "F.Mask" "F.Paste")
			(net "M_D_CPU0_SA_DQ<31>")
		)
		(pad "195" smd rect
			(at 2.050034 -20.824952 90)
			(size 0.519938 1.4986)
			(layers "F.Cu" "F.Mask" "F.Paste")
			(net "GND")
		)
		(pad "196" smd rect
			(at 2.050034 -19.975068 90)
			(size 0.519938 1.4986)
			(layers "F.Cu" "F.Mask" "F.Paste")
			(net "M_D_CPU0_SA_CB<2>")
		)
		(pad "197" smd rect
			(at 2.050034 -19.12493 90)
			(size 0.519938 1.4986)
			(layers "F.Cu" "F.Mask" "F.Paste")
			(net "GND")
		)
		(pad "198" smd rect
			(at 2.050034 -18.275046 90)
			(size 0.519938 1.4986)
			(layers "F.Cu" "F.Mask" "F.Paste")
			(net "M_D_CPU0_SA_CB<3>")
		)
		(pad "199" smd rect
			(at 2.050034 -17.424908 90)
			(size 0.519938 1.4986)
			(layers "F.Cu" "F.Mask" "F.Paste")
			(net "GND")
		)
		(pad "200" smd rect
			(at 2.050034 -16.575024 90)
			(size 0.519938 1.4986)
			(layers "F.Cu" "F.Mask" "F.Paste")
			(net "M_D_CPU0_SA_DQS_DN<9>")
		)
		(pad "201" smd rect
			(at 2.050034 -15.724886 90)
			(size 0.519938 1.4986)
			(layers "F.Cu" "F.Mask" "F.Paste")
			(net "M_D_CPU0_SA_DQS_DP<9>")
		)
		(pad "202" smd rect
			(at 2.050034 -14.875002 90)
			(size 0.519938 1.4986)
			(layers "F.Cu" "F.Mask" "F.Paste")
			(net "GND")
		)
		(pad "203" smd rect
			(at 2.050034 -14.025118 90)
			(size 0.519938 1.4986)
			(layers "F.Cu" "F.Mask" "F.Paste")
			(net "M_D_CPU0_SA_CB<6>")
		)
		(pad "204" smd rect
			(at 2.050034 -13.17498 90)
			(size 0.519938 1.4986)
			(layers "F.Cu" "F.Mask" "F.Paste")
			(net "GND")
		)
		(pad "205" smd rect
			(at 2.050034 -12.325096 90)
			(size 0.519938 1.4986)
			(layers "F.Cu" "F.Mask" "F.Paste")
			(net "M_D_CPU0_SA_CB<7>")
		)
		(pad "206" smd rect
			(at 2.050034 -11.474958 90)
			(size 0.519938 1.4986)
			(layers "F.Cu" "F.Mask" "F.Paste")
			(net "GND")
		)
		(pad "207" smd rect
			(at 2.050034 -10.625074 90)
			(size 0.519938 1.4986)
			(layers "F.Cu" "F.Mask" "F.Paste")
			(net "M_D_CPU0_RESET_N")
		)
		(pad "208" smd rect
			(at 2.050034 -9.774936 90)
			(size 0.519938 1.4986)
			(layers "F.Cu" "F.Mask" "F.Paste")
			(net "GND")
		)
		(pad "209" smd rect
			(at 2.050034 -8.925052 90)
			(size 0.519938 1.4986)
			(layers "F.Cu" "F.Mask" "F.Paste")
			(net "M_D_CPU0_SA_CS_N<1>")
		)
		(pad "210" smd rect
			(at 2.050034 -8.074914 90)
			(size 0.519938 1.4986)
			(layers "F.Cu" "F.Mask" "F.Paste")
			(net "GND")
		)
		(pad "211" smd rect
			(at 2.050034 -7.22503 90)
			(size 0.519938 1.4986)
			(layers "F.Cu" "F.Mask" "F.Paste")
			(net "M_D_CPU0_SA_CA<1>")
		)
		(pad "212" smd rect
			(at 2.050034 -6.374892 90)
			(size 0.519938 1.4986)
			(layers "F.Cu" "F.Mask" "F.Paste")
			(net "GND")
		)
		(pad "213" smd rect
			(at 2.050034 -5.525008 90)
			(size 0.519938 1.4986)
			(layers "F.Cu" "F.Mask" "F.Paste")
			(net "M_D_CPU0_SA_CA<3>")
		)
		(pad "214" smd rect
			(at 2.050034 -4.675124 90)
			(size 0.519938 1.4986)
			(layers "F.Cu" "F.Mask" "F.Paste")
			(net "GND")
		)
		(pad "215" smd rect
			(at 2.050034 -3.824986 90)
			(size 0.519938 1.4986)
			(layers "F.Cu" "F.Mask" "F.Paste")
			(net "M_D_CPU0_SA_CA<5>")
		)
		(pad "216" smd rect
			(at 2.050034 -2.975102 90)
			(size 0.519938 1.4986)
			(layers "F.Cu" "F.Mask" "F.Paste")
			(net "GND")
		)
		(pad "217" smd rect
			(at 2.050034 -2.124964 90)
			(size 0.519938 1.4986)
			(layers "F.Cu" "F.Mask" "F.Paste")
			(net "M_D_CPU0_CLK_DP<0>")
		)
		(pad "218" smd rect
			(at 2.050034 -1.27508 90)
			(size 0.519938 1.4986)
			(layers "F.Cu" "F.Mask" "F.Paste")
			(net "M_D_CPU0_CLK_DN<0>")
		)
		(pad "219" smd rect
			(at 2.050034 -0.424942 90)
			(size 0.519938 1.4986)
			(layers "F.Cu" "F.Mask" "F.Paste")
			(net "GND")
		)
		(pad "220" smd rect
			(at 2.050034 5.525008 90)
			(size 0.519938 1.4986)
			(layers "F.Cu" "F.Mask" "F.Paste")
			(net "Net_2295")
		)
		(pad "221" smd rect
			(at 2.050034 6.374892 90)
			(size 0.519938 1.4986)
			(layers "F.Cu" "F.Mask" "F.Paste")
			(net "M_D_CPU0_SB_CA<1>")
		)
		(pad "222" smd rect
			(at 2.050034 7.22503 90)
			(size 0.519938 1.4986)
			(layers "F.Cu" "F.Mask" "F.Paste")
			(net "GND")
		)
		(pad "223" smd rect
			(at 2.050034 8.074914 90)
			(size 0.519938 1.4986)
			(layers "F.Cu" "F.Mask" "F.Paste")
			(net "M_D_CPU0_SB_CA<3>")
		)
		(pad "224" smd rect
			(at 2.050034 8.925052 90)
			(size 0.519938 1.4986)
			(layers "F.Cu" "F.Mask" "F.Paste")
			(net "GND")
		)
		(pad "225" smd rect
			(at 2.050034 9.774936 90)
			(size 0.519938 1.4986)
			(layers "F.Cu" "F.Mask" "F.Paste")
			(net "M_D_CPU0_SB_CA<5>")
		)
		(pad "226" smd rect
			(at 2.050034 10.625074 90)
			(size 0.519938 1.4986)
			(layers "F.Cu" "F.Mask" "F.Paste")
			(net "GND")
		)
		(pad "227" smd rect
			(at 2.050034 11.474958 90)
			(size 0.519938 1.4986)
			(layers "F.Cu" "F.Mask" "F.Paste")
			(net "M_D_CPU0_SB_PAR")
		)
		(pad "228" smd rect
			(at 2.050034 12.325096 90)
			(size 0.519938 1.4986)
			(layers "F.Cu" "F.Mask" "F.Paste")
			(net "GND")
		)
		(pad "229" smd rect
			(at 2.050034 13.17498 90)
			(size 0.519938 1.4986)
			(layers "F.Cu" "F.Mask" "F.Paste")
			(net "M_D_CPU0_SB_CS_N<1>")
		)
		(pad "230" smd rect
			(at 2.050034 14.025118 90)
			(size 0.519938 1.4986)
			(layers "F.Cu" "F.Mask" "F.Paste")
			(net "GND")
		)
	)
)
